FILE_TYPE=LIBRARY_PARTS;
primitive 'CONN2_AAABAT029Y19';
  pin
    '1':
      PIN_NUMBER='(1)';
      PINUSE='POWER';
      NO_LOAD_CHECK='Both';
      NO_IO_CHECK='Both';
      NO_ASSERT_CHECK='TRUE';
      NO_DIR_CHECK='TRUE';
      ALLOW_CONNECT='TRUE';
    '2':
      PIN_NUMBER='(2)';
      PINUSE='POWER';
      NO_LOAD_CHECK='Both';
      NO_IO_CHECK='Both';
      NO_ASSERT_CHECK='TRUE';
      NO_DIR_CHECK='TRUE';
      ALLOW_CONNECT='TRUE';
  end_pin;
  body
    PART_NAME='CONN2_AAABAT029Y19';
    BODY_NAME='CONN2_AAABAT029Y19';
    PHYS_DES_PREFIX='BT';
    CLASS='DISCRETE';
  end_body;
end_primitive;

END.
